# S9S_MB_2U (Grand Teton) — schematic netlist excerpt (pin names and nets, part order shuffled) for the footprints in the layout excerpt that follows; sources: Cadence DE-HDL packaged netlist, KiCad conversion of 03242023_DA0F0TMBIJ0_F0T_Motherboard_J_brd_V01_OCP.brd

PR289  Q_RES  0 5% CHIP  pkg 0402LF  page 288 : A = PVCCIN_CPU1_VOS8 ; B = PVCCIN_CPU1
R325  Q_RES  10K 1% CHIP  pkg 0402LF  page 80 : A = P3V3_AUX ; B = PU_S3M_CPU1_CPLD_STATUS
PC237_P0_7  Q_CAP  22UF 16V 20% X6S  pkg C0805  page 270 : A = SW_P12V_PVCCIN_CPU0_FLT ; B = GND

(kicad_pcb
	(version 20260206)
	(generator "pcbnew")
	(generator_version "10.0")
	(general
		(thickness 1.6)
		(legacy_teardrops no)
	)
	(paper "A4")
	(title_block
		(title "03242023_DA0F0TMBIJ0_F0T_Motherboard_J_brd_V01_OCP.brd")
		(comment 1 "Grand Teton / footprints 5373-5375 of 6105")
	)
	(layers
		(0 "F.Cu" signal "TOP")
		(4 "In1.Cu" signal "GND")
		(6 "In2.Cu" signal "IN1")
		(8 "In3.Cu" signal "GND1")
		(10 "In4.Cu" signal "IN2")
		(12 "In5.Cu" signal "GND2")
		(14 "In6.Cu" signal "IN3")
		(16 "In7.Cu" signal "GND3")
		(18 "In8.Cu" signal "VCC")
		(20 "In9.Cu" signal "VCC1")
		(22 "In10.Cu" signal "GND4")
		(24 "In11.Cu" signal "IN4")
		(26 "In12.Cu" signal "GND5")
		(28 "In13.Cu" signal "IN5")
		(30 "In14.Cu" signal "GND6")
		(32 "In15.Cu" signal "IN6")
		(34 "In16.Cu" signal "GND7")
		(2 "B.Cu" signal "BOTTOM")
		(9 "F.Adhes" user "F.Adhesive")
		(11 "B.Adhes" user "B.Adhesive")
		(13 "F.Paste" user "Package Geometry/Pastemask Top")
		(15 "B.Paste" user "Package Geometry/Pastemask Bottom")
		(5 "F.SilkS" user "Ref Des/Silkscreen Top")
		(7 "B.SilkS" user "Ref Des/Silkscreen Bottom")
		(1 "F.Mask" user "Board Geometry/Soldermask Top")
		(3 "B.Mask" user "Board Geometry/Soldermask Bottom")
		(17 "Dwgs.User" user "User.Drawings")
		(19 "Cmts.User" user "User.Comments")
		(21 "Eco1.User" user "User.Eco1")
		(23 "Eco2.User" user "User.Eco2")
		(25 "Edge.Cuts" user "Board Geometry/Outline")
		(27 "Margin" user)
		(31 "F.CrtYd" user "Package Geometry/Place Bound Top")
		(29 "B.CrtYd" user "Package Geometry/Place Bound Bottom")
		(35 "F.Fab" user "Ref Des/Assembly Top")
		(33 "B.Fab" user "Ref Des/Assembly Bottom")
	)
	(footprint ""
		(layer "B.Cu")
		(at 134.347966 -345.463114 -90)
		(property "Reference" "PR289"
			(at 0 0 90)
			(layer "B.SilkS")
			(hide yes)
			(effects
				(font
					(size 1.27 1.27)
				)
				(justify mirror)
			)
		)
		(property "Value" ""
			(at 0 0 90)
			(layer "B.Fab")
			(effects
				(font
					(size 1.27 1.27)
				)
				(justify mirror)
			)
		)
		(duplicate_pad_numbers_are_jumpers no)
		(fp_line
			(start -0.7874 0.4064)
			(end 0.7874 0.4064)
			(stroke
				(width 0.1524)
				(type default)
			)
			(layer "B.SilkS")
		)
		(fp_line
			(start 0.7874 0.4064)
			(end 0.7874 -0.4064)
			(stroke
				(width 0.1524)
				(type default)
			)
			(layer "B.SilkS")
		)
		(fp_line
			(start -0.7874 -0.4064)
			(end -0.7874 0.4064)
			(stroke
				(width 0.1524)
				(type default)
			)
			(layer "B.SilkS")
		)
		(fp_line
			(start 0.7874 -0.4064)
			(end -0.7874 -0.4064)
			(stroke
				(width 0.1524)
				(type default)
			)
			(layer "B.SilkS")
		)
		(fp_line
			(start -0.67945 0.3048)
			(end -0.120396 0.3048)
			(stroke
				(width 0.1)
				(type default)
			)
			(layer "B.Fab")
		)
		(fp_line
			(start -0.120396 0.3048)
			(end -0.120396 0.2794)
			(stroke
				(width 0.1)
				(type default)
			)
			(layer "B.Fab")
		)
		(fp_line
			(start 0.12065 0.3048)
			(end 0.67945 0.3048)
			(stroke
				(width 0.1)
				(type default)
			)
			(layer "B.Fab")
		)
		(fp_line
			(start 0.67945 0.3048)
			(end 0.67945 -0.305054)
			(stroke
				(width 0.1)
				(type default)
			)
			(layer "B.Fab")
		)
		(fp_line
			(start -0.120396 0.2794)
			(end 0.12065 0.2794)
			(stroke
				(width 0.1)
				(type default)
			)
			(layer "B.Fab")
		)
		(fp_line
			(start 0.12065 0.2794)
			(end 0.12065 0.3048)
			(stroke
				(width 0.1)
				(type default)
			)
			(layer "B.Fab")
		)
		(fp_line
			(start -0.12065 -0.2794)
			(end -0.12065 -0.3048)
			(stroke
				(width 0.1)
				(type default)
			)
			(layer "B.Fab")
		)
		(fp_line
			(start 0.12065 -0.2794)
			(end -0.12065 -0.2794)
			(stroke
				(width 0.1)
				(type default)
			)
			(layer "B.Fab")
		)
		(fp_line
			(start -0.67945 -0.3048)
			(end -0.67945 0.3048)
			(stroke
				(width 0.1)
				(type default)
			)
			(layer "B.Fab")
		)
		(fp_line
			(start -0.12065 -0.3048)
			(end -0.67945 -0.3048)
			(stroke
				(width 0.1)
				(type default)
			)
			(layer "B.Fab")
		)
		(fp_line
			(start 0.12065 -0.305054)
			(end 0.12065 -0.2794)
			(stroke
				(width 0.1)
				(type default)
			)
			(layer "B.Fab")
		)
		(fp_line
			(start 0.67945 -0.305054)
			(end 0.12065 -0.305054)
			(stroke
				(width 0.1)
				(type default)
			)
			(layer "B.Fab")
		)
		(pad "1" smd circle
			(at 0.40005 0 90)
			(size 0 0)
			(layers "B.Cu" "B.Mask" "B.Paste")
			(net "PVCCIN_CPU1_VOS8")
		)
		(pad "2" smd circle
			(at -0.40005 0 90)
			(size 0 0)
			(layers "B.Cu" "B.Mask" "B.Paste")
			(net "PVCCIN_CPU1")
		)
	)
	(footprint ""
		(layer "B.Cu")
		(at 181.530752 -192.699894 -90)
		(property "Reference" "R325"
			(at 0 0 90)
			(layer "B.SilkS")
			(hide yes)
			(effects
				(font
					(size 1.27 1.27)
				)
				(justify mirror)
			)
		)
		(property "Value" ""
			(at 0 0 90)
			(layer "B.Fab")
			(effects
				(font
					(size 1.27 1.27)
				)
				(justify mirror)
			)
		)
		(duplicate_pad_numbers_are_jumpers no)
		(fp_line
			(start -0.7874 0.4064)
			(end 0.7874 0.4064)
			(stroke
				(width 0.1524)
				(type default)
			)
			(layer "B.SilkS")
		)
		(fp_line
			(start 0.7874 0.4064)
			(end 0.7874 -0.4064)
			(stroke
				(width 0.1524)
				(type default)
			)
			(layer "B.SilkS")
		)
		(fp_line
			(start -0.7874 -0.4064)
			(end -0.7874 0.4064)
			(stroke
				(width 0.1524)
				(type default)
			)
			(layer "B.SilkS")
		)
		(fp_line
			(start 0.7874 -0.4064)
			(end -0.7874 -0.4064)
			(stroke
				(width 0.1524)
				(type default)
			)
			(layer "B.SilkS")
		)
		(fp_line
			(start -0.67945 0.3048)
			(end -0.120396 0.3048)
			(stroke
				(width 0.1)
				(type default)
			)
			(layer "B.Fab")
		)
		(fp_line
			(start -0.120396 0.3048)
			(end -0.120396 0.2794)
			(stroke
				(width 0.1)
				(type default)
			)
			(layer "B.Fab")
		)
		(fp_line
			(start 0.12065 0.3048)
			(end 0.67945 0.3048)
			(stroke
				(width 0.1)
				(type default)
			)
			(layer "B.Fab")
		)
		(fp_line
			(start 0.67945 0.3048)
			(end 0.67945 -0.305054)
			(stroke
				(width 0.1)
				(type default)
			)
			(layer "B.Fab")
		)
		(fp_line
			(start -0.120396 0.2794)
			(end 0.12065 0.2794)
			(stroke
				(width 0.1)
				(type default)
			)
			(layer "B.Fab")
		)
		(fp_line
			(start 0.12065 0.2794)
			(end 0.12065 0.3048)
			(stroke
				(width 0.1)
				(type default)
			)
			(layer "B.Fab")
		)
		(fp_line
			(start -0.12065 -0.2794)
			(end -0.12065 -0.3048)
			(stroke
				(width 0.1)
				(type default)
			)
			(layer "B.Fab")
		)
		(fp_line
			(start 0.12065 -0.2794)
			(end -0.12065 -0.2794)
			(stroke
				(width 0.1)
				(type default)
			)
			(layer "B.Fab")
		)
		(fp_line
			(start -0.67945 -0.3048)
			(end -0.67945 0.3048)
			(stroke
				(width 0.1)
				(type default)
			)
			(layer "B.Fab")
		)
		(fp_line
			(start -0.12065 -0.3048)
			(end -0.67945 -0.3048)
			(stroke
				(width 0.1)
				(type default)
			)
			(layer "B.Fab")
		)
		(fp_line
			(start 0.12065 -0.305054)
			(end 0.12065 -0.2794)
			(stroke
				(width 0.1)
				(type default)
			)
			(layer "B.Fab")
		)
		(fp_line
			(start 0.67945 -0.305054)
			(end 0.12065 -0.305054)
			(stroke
				(width 0.1)
				(type default)
			)
			(layer "B.Fab")
		)
		(pad "1" smd circle
			(at 0.40005 0 90)
			(size 0 0)
			(layers "B.Cu" "B.Mask" "B.Paste")
			(net "P3V3_AUX")
		)
		(pad "2" smd circle
			(at -0.40005 0 90)
			(size 0 0)
			(layers "B.Cu" "B.Mask" "B.Paste")
			(net "PU_S3M_CPU1_CPLD_STATUS")
		)
	)
	(footprint ""
		(layer "B.Cu")
		(at 331.873352 -342.936576 90)
		(property "Reference" "PC237_P0_7"
			(at 0 0 90)
			(layer "B.SilkS")
			(hide yes)
			(effects
				(font
					(size 1.27 1.27)
				)
				(justify mirror)
			)
		)
		(property "Value" ""
			(at 0 0 90)
			(layer "B.Fab")
			(effects
				(font
					(size 1.27 1.27)
				)
				(justify mirror)
			)
		)
		(duplicate_pad_numbers_are_jumpers no)
		(fp_line
			(start 1.524 -0.762)
			(end -1.524 -0.762)
			(stroke
				(width 0.1524)
				(type default)
			)
			(layer "B.SilkS")
		)
		(fp_line
			(start -1.524 -0.762)
			(end -1.524 0.762)
			(stroke
				(width 0.1524)
				(type default)
			)
			(layer "B.SilkS")
		)
		(fp_line
			(start 1.524 0.762)
			(end 1.524 -0.762)
			(stroke
				(width 0.1524)
				(type default)
			)
			(layer "B.SilkS")
		)
		(fp_line
			(start -1.524 0.762)
			(end 1.524 0.762)
			(stroke
				(width 0.1524)
				(type default)
			)
			(layer "B.SilkS")
		)
		(fp_line
			(start 1.1049 -0.724916)
			(end 1.1049 0.724916)
			(stroke
				(width 0.1)
				(type default)
			)
			(layer "B.Fab")
		)
		(fp_line
			(start -1.1049 -0.724916)
			(end 1.1049 -0.724916)
			(stroke
				(width 0.1)
				(type default)
			)
			(layer "B.Fab")
		)
		(fp_line
			(start 1.1049 0.724916)
			(end -1.1049 0.724916)
			(stroke
				(width 0.1)
				(type default)
			)
			(layer "B.Fab")
		)
		(fp_line
			(start -1.1049 0.724916)
			(end -1.1049 -0.724916)
			(stroke
				(width 0.1)
				(type default)
			)
			(layer "B.Fab")
		)
		(pad "1" smd rect
			(at 0.889 0 90)
			(size 1.016 1.27)
			(layers "B.Cu" "B.Mask" "B.Paste")
			(net "SW_P12V_PVCCIN_CPU0_FLT")
		)
		(pad "2" smd rect
			(at -0.889 0 90)
			(size 1.016 1.27)
			(layers "B.Cu" "B.Mask" "B.Paste")
			(net "GND")
		)
	)
)
